# BASEBOARD_FAB2 (Tioga Pass) — schematic netlist excerpt (pin names and nets, part order shuffled) for the footprints in the layout excerpt that follows; sources: Cadence DE-HDL packaged netlist, KiCad conversion of Wiwynn_Tioga_Pass_MB.brd

C6R5  CAPP  470UF 2.5V 20% ALUM  pkg 3018  page 214 : A = PVCCIO_CPU1 ; B = GND
C5G105  CAP_A  22.0UF 4V 20% X6S  pkg 0603V  page 243 : A = PVDDQ_KLM ; B = GND
R9M19  RES  240 1.0% CHIP  pkg 0402  page 163 : A = PVCCIO_CPU1 ; B = SMB_CPU1_PE_HP_GTL_R_SCL

(kicad_pcb
	(version 20260206)
	(generator "pcbnew")
	(generator_version "10.0")
	(general
		(thickness 1.6)
		(legacy_teardrops no)
	)
	(paper "A4")
	(title_block
		(title "Wiwynn_Tioga_Pass_MB.brd")
		(comment 1 "Tioga Pass / footprints 3118-3120 of 4770")
	)
	(layers
		(0 "F.Cu" signal "TOP")
		(4 "In1.Cu" signal "L2GND")
		(6 "In2.Cu" signal "L3")
		(8 "In3.Cu" signal "L4GND")
		(10 "In4.Cu" signal "L5")
		(12 "In5.Cu" signal "L6GND")
		(14 "In6.Cu" signal "L7VCC")
		(16 "In7.Cu" signal "L8VCC")
		(18 "In8.Cu" signal "L9GND")
		(20 "In9.Cu" signal "L10")
		(22 "In10.Cu" signal "L11GND")
		(24 "In11.Cu" signal "L12")
		(26 "In12.Cu" signal "L13GND")
		(2 "B.Cu" signal "BOTTOM")
		(9 "F.Adhes" user "F.Adhesive")
		(11 "B.Adhes" user "B.Adhesive")
		(13 "F.Paste" user "Package Geometry/Pastemask Top")
		(15 "B.Paste" user "Package Geometry/Pastemask Bottom")
		(5 "F.SilkS" user "Ref Des/Silkscreen Top")
		(7 "B.SilkS" user "Ref Des/Silkscreen Bottom")
		(1 "F.Mask" user "Board Geometry/Soldermask Top")
		(3 "B.Mask" user "Board Geometry/Soldermask Bottom")
		(17 "Dwgs.User" user "User.Drawings")
		(19 "Cmts.User" user "User.Comments")
		(21 "Eco1.User" user "User.Eco1")
		(23 "Eco2.User" user "User.Eco2")
		(25 "Edge.Cuts" user "Board Geometry/Outline")
		(27 "Margin" user)
		(31 "F.CrtYd" user "Package Geometry/Place Bound Top")
		(29 "B.CrtYd" user "Package Geometry/Place Bound Bottom")
		(35 "F.Fab" user "Ref Des/Assembly Top")
		(33 "B.Fab" user "Ref Des/Assembly Bottom")
	)
	(footprint ""
		(layer "B.Cu")
		(at 164.973 -60.6552 90)
		(property "Reference" "C6R5"
			(at -0.02667 10.541 0)
			(unlocked yes)
			(layer "B.SilkS")
			(effects
				(font
					(size 0.7874 0.5842)
					(thickness 0.1524)
				)
				(justify mirror)
			)
		)
		(property "Value" ""
			(at 0 0 90)
			(layer "B.Fab")
			(effects
				(font
					(size 1.27 1.27)
				)
				(justify mirror)
			)
		)
		(duplicate_pad_numbers_are_jumpers no)
		(fp_line
			(start 2.563114 -1.616456)
			(end 2.563114 1.633728)
			(stroke
				(width 0.1524)
				(type default)
			)
			(layer "B.SilkS")
		)
		(fp_line
			(start 1.6002 -1.616456)
			(end 2.563114 -1.616456)
			(stroke
				(width 0.1524)
				(type default)
			)
			(layer "B.SilkS")
		)
		(fp_line
			(start -1.6002 -1.616456)
			(end -2.504948 -1.616456)
			(stroke
				(width 0.1524)
				(type default)
			)
			(layer "B.SilkS")
		)
		(fp_line
			(start -2.504948 -1.616456)
			(end -2.504948 1.633728)
			(stroke
				(width 0.1524)
				(type default)
			)
			(layer "B.SilkS")
		)
		(fp_line
			(start 2.563114 1.633728)
			(end 1.6002 1.633728)
			(stroke
				(width 0.1524)
				(type default)
			)
			(layer "B.SilkS")
		)
		(fp_line
			(start -2.504948 1.633728)
			(end -1.6002 1.633728)
			(stroke
				(width 0.1524)
				(type default)
			)
			(layer "B.SilkS")
		)
		(fp_line
			(start 2.286 7.366)
			(end 2.286 1.632712)
			(stroke
				(width 0.1524)
				(type default)
			)
			(layer "B.SilkS")
		)
		(fp_line
			(start 2.286 7.366)
			(end 1.60147 7.366)
			(stroke
				(width 0.1524)
				(type default)
			)
			(layer "B.SilkS")
		)
		(fp_line
			(start -2.286 7.366)
			(end -2.286 1.63195)
			(stroke
				(width 0.1524)
				(type default)
			)
			(layer "B.SilkS")
		)
		(fp_line
			(start -2.286 7.366)
			(end -1.600708 7.366)
			(stroke
				(width 0.1524)
				(type default)
			)
			(layer "B.SilkS")
		)
		(fp_rect
			(start 2.286 7.366)
			(end -2.286 -0.254)
			(stroke
				(width 0)
				(type default)
			)
			(fill no)
			(layer "B.CrtYd")
		)
		(fp_line
			(start 2.286 -0.254)
			(end -2.286 -0.254)
			(stroke
				(width 0.1)
				(type default)
			)
			(layer "B.Fab")
		)
		(fp_line
			(start -2.286 -0.254)
			(end -2.286 7.366)
			(stroke
				(width 0.1)
				(type default)
			)
			(layer "B.Fab")
		)
		(fp_line
			(start 2.286 7.366)
			(end 2.286 -0.254)
			(stroke
				(width 0.1)
				(type default)
			)
			(layer "B.Fab")
		)
		(fp_line
			(start -2.286 7.366)
			(end 2.286 7.366)
			(stroke
				(width 0.1)
				(type default)
			)
			(layer "B.Fab")
		)
		(pad "1" smd rect
			(at 0 0 270)
			(size 2.54 3.048)
			(layers "B.Cu" "B.Mask" "B.Paste")
			(net "PVCCIO_CPU1")
		)
		(pad "2" smd rect
			(at 0 7.112 270)
			(size 2.54 3.048)
			(layers "B.Cu" "B.Mask" "B.Paste")
			(net "GND")
		)
	)
	(footprint ""
		(layer "B.Cu")
		(at -3.47726 -117.89156)
		(property "Reference" "R9M19"
			(at 0 0 0)
			(layer "B.SilkS")
			(hide yes)
			(effects
				(font
					(size 1.27 1.27)
				)
				(justify mirror)
			)
		)
		(property "Value" ""
			(at 0 0 0)
			(layer "B.Fab")
			(effects
				(font
					(size 1.27 1.27)
				)
				(justify mirror)
			)
		)
		(duplicate_pad_numbers_are_jumpers no)
		(fp_rect
			(start -0.2794 0.9906)
			(end 0.2794 -0.1016)
			(stroke
				(width 0)
				(type default)
			)
			(fill no)
			(layer "B.CrtYd")
		)
		(fp_line
			(start -0.2794 -0.1016)
			(end 0.2794 -0.1016)
			(stroke
				(width 0.1)
				(type default)
			)
			(layer "B.Fab")
		)
		(fp_line
			(start -0.2794 0.9906)
			(end -0.2794 -0.1016)
			(stroke
				(width 0.1)
				(type default)
			)
			(layer "B.Fab")
		)
		(fp_line
			(start 0.2794 -0.1016)
			(end 0.2794 0.9906)
			(stroke
				(width 0.1)
				(type default)
			)
			(layer "B.Fab")
		)
		(fp_line
			(start 0.2794 0.9906)
			(end -0.2794 0.9906)
			(stroke
				(width 0.1)
				(type default)
			)
			(layer "B.Fab")
		)
		(pad "1" smd rect
			(at 0 0 180)
			(size 0.508 0.508)
			(layers "B.Cu" "B.Mask" "B.Paste")
			(net "PVCCIO_CPU1")
		)
		(pad "2" smd rect
			(at 0 0.889 180)
			(size 0.508 0.508)
			(layers "B.Cu" "B.Mask" "B.Paste")
			(net "SMB_CPU1_PE_HP_GTL_R_SCL")
		)
		(zone
			(layer "B.Cu")
			(hatch none 0.5)
			(connect_pads
				(clearance 0)
			)
			(min_thickness 0.25)
			(keepout
				(tracks allowed)
				(vias not_allowed)
				(pads allowed)
				(copperpour not_allowed)
				(footprints allowed)
			)
			(placement
				(enabled no)
				(sheetname "")
			)
			(fill
				(thermal_gap 0.5)
				(thermal_bridge_width 0.5)
				(island_removal_mode 0)
			)
			(polygon
				(pts
					(xy -3.73126 -117.25656) (xy -3.22326 -117.25656) (xy -3.22326 -117.63756) (xy -3.73126 -117.63756)
				)
			)
		)
		(zone
			(layer "B.Cu")
			(hatch none 0.5)
			(connect_pads
				(clearance 0)
			)
			(min_thickness 0.25)
			(keepout
				(tracks not_allowed)
				(vias allowed)
				(pads allowed)
				(copperpour not_allowed)
				(footprints allowed)
			)
			(placement
				(enabled no)
				(sheetname "")
			)
			(fill
				(thermal_gap 0.5)
				(thermal_bridge_width 0.5)
				(island_removal_mode 0)
			)
			(polygon
				(pts
					(xy -3.73126 -117.25656) (xy -3.22326 -117.25656) (xy -3.22326 -117.63756) (xy -3.73126 -117.63756)
				)
			)
		)
	)
	(footprint ""
		(layer "B.Cu")
		(at 111.000032 -149.8092 90)
		(property "Reference" "C5G105"
			(at -1.14681 0.76708 180)
			(unlocked yes)
			(layer "B.SilkS")
			(effects
				(font
					(size 0.7874 0.5842)
					(thickness 0.1524)
				)
				(justify mirror)
			)
		)
		(property "Value" ""
			(at 0 0 90)
			(layer "B.Fab")
			(effects
				(font
					(size 1.27 1.27)
				)
				(justify mirror)
			)
		)
		(duplicate_pad_numbers_are_jumpers no)
		(fp_rect
			(start -0.4953 -0.2032)
			(end 0.4953 1.6002)
			(stroke
				(width 0)
				(type default)
			)
			(fill no)
			(layer "B.CrtYd")
		)
		(fp_line
			(start 0.4953 -0.2032)
			(end -0.4953 -0.2032)
			(stroke
				(width 0.1)
				(type default)
			)
			(layer "B.Fab")
		)
		(fp_line
			(start -0.4953 -0.2032)
			(end -0.4953 1.6002)
			(stroke
				(width 0.1)
				(type default)
			)
			(layer "B.Fab")
		)
		(fp_line
			(start 0.4953 1.6002)
			(end 0.4953 -0.2032)
			(stroke
				(width 0.1)
				(type default)
			)
			(layer "B.Fab")
		)
		(fp_line
			(start -0.4953 1.6002)
			(end 0.4953 1.6002)
			(stroke
				(width 0.1)
				(type default)
			)
			(layer "B.Fab")
		)
		(pad "1" smd rect
			(at 0 0 270)
			(size 0.762 0.889)
			(layers "B.Cu" "B.Mask" "B.Paste")
			(net "PVDDQ_KLM")
		)
		(pad "2" smd rect
			(at 0 1.397 270)
			(size 0.762 0.889)
			(layers "B.Cu" "B.Mask" "B.Paste")
			(net "GND")
		)
		(zone
			(layer "B.Cu")
			(hatch none 0.5)
			(connect_pads
				(clearance 0)
			)
			(min_thickness 0.25)
			(keepout
				(tracks not_allowed)
				(vias allowed)
				(pads allowed)
				(copperpour not_allowed)
				(footprints allowed)
			)
			(placement
				(enabled no)
				(sheetname "")
			)
			(fill
				(thermal_gap 0.5)
				(thermal_bridge_width 0.5)
				(island_removal_mode 0)
			)
			(polygon
				(pts
					(xy 111.444532 -149.4282) (xy 111.952532 -149.4282) (xy 111.952532 -150.1902) (xy 111.444532 -150.1902)
				)
			)
		)
	)
)
